(kicad_pcb
	(version 20211014)
	(generator pcbnew)
	(general
    (thickness 1.6)
  )
	(paper "A4")
	(title_block
    (title "SA800U (Snapdragon 845) Baseboard")
    (date "2023-10-19")
    (rev "1.0.3")
    (company "Antmicro Ltd.")
    (comment 1 "www.antmicro.com")
		(comment 9 "footprints 580-589 of 589")
	)
	(layers
    (0 "F.Cu" signal)
    (1 "In1.Cu" power)
    (2 "In2.Cu" signal)
    (3 "In3.Cu" signal)
    (4 "In4.Cu" power)
    (31 "B.Cu" signal)
    (32 "B.Adhes" user "B.Adhesive")
    (33 "F.Adhes" user "F.Adhesive")
    (34 "B.Paste" user)
    (35 "F.Paste" user)
    (36 "B.SilkS" user "B.Silkscreen")
    (37 "F.SilkS" user "F.Silkscreen")
    (38 "B.Mask" user)
    (39 "F.Mask" user)
    (40 "Dwgs.User" user "User.Drawings")
    (41 "Cmts.User" user "User.Comments")
    (42 "Eco1.User" user "User.Eco1")
    (43 "Eco2.User" user "User.Eco2")
    (44 "Edge.Cuts" user)
    (45 "Margin" user)
    (46 "B.CrtYd" user "B.Courtyard")
    (47 "F.CrtYd" user "F.Courtyard")
    (48 "B.Fab" user)
    (49 "F.Fab" user)
  )
	(footprint "sa800u-baseboard-hw-footprints:TP_SMD_0.75mm" (layer "B.Cu")
    (tedit 5E4A9375)
    (at 110.4 97.2)
    (property "Author" "Antmicro")
    (property "License" "Apache-2.0")
    (property "MPN" "")
    (property "Manufacturer" "")
    (property "Sheetfile" "camera-interface.kicad_sch")
    (property "Sheetname" "Camera Interface")
    (attr smd)
    (fp_text reference "TP29" (at 0.44 0.34 270) (layer "B.SilkS")
      (effects (font (size 0.7 0.7) (thickness 0.15)) (justify left bottom mirror))
    )
    (fp_text value "TP_0.75mm_SMD" (at 0 -1.2 180) (layer "B.Fab")
      (effects (font (size 0.7 0.7) (thickness 0.15)) (justify left bottom mirror))
    )
    (fp_text user "${REFERENCE}" (at -0.4 -2.7 180) (layer "B.Fab") hide
      (effects (font (size 0.7 0.7) (thickness 0.15)) (justify left bottom mirror))
    )
    (fp_text user "License: Apache-2.0" (at -0.4 -5.101 180) (layer "B.Fab") hide
      (effects (font (size 0.7 0.7) (thickness 0.15)) (justify left bottom mirror))
    )
    (fp_text user "Author: Antmicro" (at -0.4 -3.901 180) (layer "B.Fab") hide
      (effects (font (size 0.7 0.7) (thickness 0.15)) (justify left bottom mirror))
    )
    (pad "1" smd circle (at 0 0) (size 0.75 0.75) (layers "B.Cu" "B.Mask")
      (net 45 "CCI1_I2C_SDA") (pinfunction "1") (pintype "passive"))
  )
	(footprint "sa800u-baseboard-hw-footprints:TP_SMD_0.75mm" (layer "B.Cu")
    (tedit 5E4A9375)
    (at 111.8 97.2)
    (property "Author" "Antmicro")
    (property "License" "Apache-2.0")
    (property "MPN" "")
    (property "Manufacturer" "")
    (property "Sheetfile" "camera-interface.kicad_sch")
    (property "Sheetname" "Camera Interface")
    (attr smd)
    (fp_text reference "TP31" (at 0.4 0.34 270) (layer "B.SilkS")
      (effects (font (size 0.7 0.7) (thickness 0.15)) (justify left bottom mirror))
    )
    (fp_text value "TP_0.75mm_SMD" (at 0 -1.2 180) (layer "B.Fab")
      (effects (font (size 0.7 0.7) (thickness 0.15)) (justify left bottom mirror))
    )
    (fp_text user "Author: Antmicro" (at -0.4 -3.901 180) (layer "B.Fab") hide
      (effects (font (size 0.7 0.7) (thickness 0.15)) (justify left bottom mirror))
    )
    (fp_text user "License: Apache-2.0" (at -0.4 -5.101 180) (layer "B.Fab") hide
      (effects (font (size 0.7 0.7) (thickness 0.15)) (justify left bottom mirror))
    )
    (fp_text user "${REFERENCE}" (at -0.4 -2.7 180) (layer "B.Fab") hide
      (effects (font (size 0.7 0.7) (thickness 0.15)) (justify left bottom mirror))
    )
    (pad "1" smd circle (at 0 0) (size 0.75 0.75) (layers "B.Cu" "B.Mask")
      (net 44 "CCI1_I2C_SCL") (pinfunction "1") (pintype "passive"))
  )
	(footprint "sa800u-baseboard-hw-footprints:TP_SMD_0.75mm" (layer "B.Cu")
    (tedit 5E4A9375)
    (at 111.2 94.6)
    (property "Author" "Antmicro")
    (property "License" "Apache-2.0")
    (property "MPN" "")
    (property "Manufacturer" "")
    (property "Sheetfile" "camera-interface.kicad_sch")
    (property "Sheetname" "Camera Interface")
    (attr smd)
    (fp_text reference "TP32" (at 3 0.86 180) (layer "B.SilkS")
      (effects (font (size 0.7 0.7) (thickness 0.15)) (justify left bottom mirror))
    )
    (fp_text value "TP_0.75mm_SMD" (at 0 -1.2 180) (layer "B.Fab")
      (effects (font (size 0.7 0.7) (thickness 0.15)) (justify left bottom mirror))
    )
    (fp_text user "Author: Antmicro" (at -0.4 -3.901 180) (layer "B.Fab") hide
      (effects (font (size 0.7 0.7) (thickness 0.15)) (justify left bottom mirror))
    )
    (fp_text user "${REFERENCE}" (at -0.4 -2.7 180) (layer "B.Fab") hide
      (effects (font (size 0.7 0.7) (thickness 0.15)) (justify left bottom mirror))
    )
    (fp_text user "License: Apache-2.0" (at -0.4 -5.101 180) (layer "B.Fab") hide
      (effects (font (size 0.7 0.7) (thickness 0.15)) (justify left bottom mirror))
    )
    (pad "1" smd circle (at 0 0) (size 0.75 0.75) (layers "B.Cu" "B.Mask")
      (net 42 "CCI0_I2C_SCL") (pinfunction "1") (pintype "passive"))
  )
	(footprint "sa800u-baseboard-hw-footprints:TP_SMD_0.75mm" (layer "B.Cu")
    (tedit 5E4A9375)
    (at 117.35 94.4992)
    (property "Author" "Antmicro")
    (property "License" "Apache-2.0")
    (property "MPN" "")
    (property "Manufacturer" "")
    (property "Sheetfile" "camera-interface.kicad_sch")
    (property "Sheetname" "Camera Interface")
    (attr smd)
    (fp_text reference "TP33" (at 1.25 -0.4892 180) (layer "B.SilkS")
      (effects (font (size 0.7 0.7) (thickness 0.15)) (justify left bottom mirror))
    )
    (fp_text value "TP_0.75mm_SMD" (at 0 -1.2 180) (layer "B.Fab")
      (effects (font (size 0.7 0.7) (thickness 0.15)) (justify left bottom mirror))
    )
    (fp_text user "License: Apache-2.0" (at -0.4 -5.101 180) (layer "B.Fab") hide
      (effects (font (size 0.7 0.7) (thickness 0.15)) (justify left bottom mirror))
    )
    (fp_text user "Author: Antmicro" (at -0.4 -3.901 180) (layer "B.Fab") hide
      (effects (font (size 0.7 0.7) (thickness 0.15)) (justify left bottom mirror))
    )
    (fp_text user "${REFERENCE}" (at -0.4 -2.7 180) (layer "B.Fab") hide
      (effects (font (size 0.7 0.7) (thickness 0.15)) (justify left bottom mirror))
    )
    (pad "1" smd circle (at 0 0) (size 0.75 0.75) (layers "B.Cu" "B.Mask")
      (net 353 "Net-(C108-Pad1)") (pinfunction "1") (pintype "passive"))
  )
	(footprint "sa800u-baseboard-hw-footprints:TP_SMD_0.75mm" (layer "B.Cu")
    (tedit 5E4A9375)
    (at 114.1 92)
    (property "Author" "Antmicro")
    (property "License" "Apache-2.0")
    (property "MPN" "")
    (property "Manufacturer" "")
    (property "Sheetfile" "camera-interface.kicad_sch")
    (property "Sheetname" "Camera Interface")
    (attr smd)
    (fp_text reference "TP35" (at 1.43 -0.5 180) (layer "B.SilkS")
      (effects (font (size 0.7 0.7) (thickness 0.15)) (justify left bottom mirror))
    )
    (fp_text value "TP_0.75mm_SMD" (at 0 -1.2 180) (layer "B.Fab")
      (effects (font (size 0.7 0.7) (thickness 0.15)) (justify left bottom mirror))
    )
    (fp_text user "${REFERENCE}" (at -0.4 -2.7 180) (layer "B.Fab") hide
      (effects (font (size 0.7 0.7) (thickness 0.15)) (justify left bottom mirror))
    )
    (fp_text user "License: Apache-2.0" (at -0.4 -5.101 180) (layer "B.Fab") hide
      (effects (font (size 0.7 0.7) (thickness 0.15)) (justify left bottom mirror))
    )
    (fp_text user "Author: Antmicro" (at -0.4 -3.901 180) (layer "B.Fab") hide
      (effects (font (size 0.7 0.7) (thickness 0.15)) (justify left bottom mirror))
    )
    (pad "1" smd circle (at 0 0) (size 0.75 0.75) (layers "B.Cu" "B.Mask")
      (net 293 "/Camera Interface/CCI1_I2C_SCL_3V3") (pinfunction "1") (pintype "passive"))
  )
	(footprint "sa800u-baseboard-hw-footprints:TP_SMD_0.75mm" (layer "B.Cu")
    (tedit 5E4A9375)
    (at 107.6 97.2)
    (property "Author" "Antmicro")
    (property "License" "Apache-2.0")
    (property "MPN" "")
    (property "Manufacturer" "")
    (property "Sheetfile" "camera-interface.kicad_sch")
    (property "Sheetname" "Camera Interface")
    (attr smd)
    (fp_text reference "TP39" (at 0.38 0.32 270) (layer "B.SilkS")
      (effects (font (size 0.7 0.7) (thickness 0.15)) (justify left bottom mirror))
    )
    (fp_text value "TP_0.75mm_SMD" (at 0 -1.2 180) (layer "B.Fab")
      (effects (font (size 0.7 0.7) (thickness 0.15)) (justify left bottom mirror))
    )
    (fp_text user "License: Apache-2.0" (at -0.4 -5.101 180) (layer "B.Fab") hide
      (effects (font (size 0.7 0.7) (thickness 0.15)) (justify left bottom mirror))
    )
    (fp_text user "${REFERENCE}" (at -0.4 -2.7 180) (layer "B.Fab") hide
      (effects (font (size 0.7 0.7) (thickness 0.15)) (justify left bottom mirror))
    )
    (fp_text user "Author: Antmicro" (at -0.4 -3.901 180) (layer "B.Fab") hide
      (effects (font (size 0.7 0.7) (thickness 0.15)) (justify left bottom mirror))
    )
    (pad "1" smd circle (at 0 0) (size 0.75 0.75) (layers "B.Cu" "B.Mask")
      (net 15 "CAM0_RST") (pinfunction "1") (pintype "passive"))
  )
	(footprint "sa800u-baseboard-hw-footprints:TP_SMD_0.75mm" (layer "B.Cu")
    (tedit 5E4A9375)
    (at 106.2 97.2)
    (property "Author" "Antmicro")
    (property "License" "Apache-2.0")
    (property "MPN" "")
    (property "Manufacturer" "")
    (property "Sheetfile" "camera-interface.kicad_sch")
    (property "Sheetname" "Camera Interface")
    (attr smd)
    (fp_text reference "TP40" (at 0.41 0.29 270) (layer "B.SilkS")
      (effects (font (size 0.7 0.7) (thickness 0.15)) (justify left bottom mirror))
    )
    (fp_text value "TP_0.75mm_SMD" (at 0 -1.2 180) (layer "B.Fab")
      (effects (font (size 0.7 0.7) (thickness 0.15)) (justify left bottom mirror))
    )
    (fp_text user "Author: Antmicro" (at -0.4 -3.901 180) (layer "B.Fab") hide
      (effects (font (size 0.7 0.7) (thickness 0.15)) (justify left bottom mirror))
    )
    (fp_text user "${REFERENCE}" (at -0.4 -2.7 180) (layer "B.Fab") hide
      (effects (font (size 0.7 0.7) (thickness 0.15)) (justify left bottom mirror))
    )
    (fp_text user "License: Apache-2.0" (at -0.4 -5.101 180) (layer "B.Fab") hide
      (effects (font (size 0.7 0.7) (thickness 0.15)) (justify left bottom mirror))
    )
    (pad "1" smd circle (at 0 0) (size 0.75 0.75) (layers "B.Cu" "B.Mask")
      (net 14 "CAM0_PWDN") (pinfunction "1") (pintype "passive"))
  )
	(footprint "sa800u-baseboard-hw-footprints:TP_SMD_0.75mm" (layer "B.Cu")
    (tedit 5E4A9375)
    (at 109 97.2)
    (property "Author" "Antmicro")
    (property "License" "Apache-2.0")
    (property "MPN" "")
    (property "Manufacturer" "")
    (property "Sheetfile" "camera-interface.kicad_sch")
    (property "Sheetname" "Camera Interface")
    (attr smd)
    (fp_text reference "TP41" (at 0.39 0.35 270) (layer "B.SilkS")
      (effects (font (size 0.7 0.7) (thickness 0.15)) (justify left bottom mirror))
    )
    (fp_text value "TP_0.75mm_SMD" (at 0 -1.2 180) (layer "B.Fab")
      (effects (font (size 0.7 0.7) (thickness 0.15)) (justify left bottom mirror))
    )
    (fp_text user "${REFERENCE}" (at -0.4 -2.7 180) (layer "B.Fab") hide
      (effects (font (size 0.7 0.7) (thickness 0.15)) (justify left bottom mirror))
    )
    (fp_text user "Author: Antmicro" (at -0.4 -3.901 180) (layer "B.Fab") hide
      (effects (font (size 0.7 0.7) (thickness 0.15)) (justify left bottom mirror))
    )
    (fp_text user "License: Apache-2.0" (at -0.4 -5.101 180) (layer "B.Fab") hide
      (effects (font (size 0.7 0.7) (thickness 0.15)) (justify left bottom mirror))
    )
    (pad "1" smd circle (at 0 0) (size 0.75 0.75) (layers "B.Cu" "B.Mask")
      (net 16 "CAM1_PWDN") (pinfunction "1") (pintype "passive"))
  )
	(footprint "sa800u-baseboard-hw-footprints:TP_SMD_0.75mm" (layer "B.Cu")
    (tedit 5E4A9375)
    (at 82.25 86.5)
    (property "Author" "Antmicro")
    (property "License" "Apache-2.0")
    (property "MPN" "")
    (property "Manufacturer" "")
    (property "Sheetfile" "som.kicad_sch")
    (property "Sheetname" "SoM")
    (attr smd)
    (fp_text reference "TP112" (at 1.33 -0.57 180) (layer "B.SilkS")
      (effects (font (size 0.7 0.7) (thickness 0.15)) (justify left bottom mirror))
    )
    (fp_text value "TP_0.75mm_SMD" (at 0 -1.2 180) (layer "B.Fab")
      (effects (font (size 0.7 0.7) (thickness 0.15)) (justify left bottom mirror))
    )
    (fp_text user "License: Apache-2.0" (at -0.4 -5.101 180) (layer "B.Fab") hide
      (effects (font (size 0.7 0.7) (thickness 0.15)) (justify left bottom mirror))
    )
    (fp_text user "${REFERENCE}" (at -0.4 -2.7 180) (layer "B.Fab") hide
      (effects (font (size 0.7 0.7) (thickness 0.15)) (justify left bottom mirror))
    )
    (fp_text user "Author: Antmicro" (at -0.4 -3.901 180) (layer "B.Fab") hide
      (effects (font (size 0.7 0.7) (thickness 0.15)) (justify left bottom mirror))
    )
    (pad "1" smd circle (at 0 0) (size 0.75 0.75) (layers "B.Cu" "B.Mask")
      (net 424 "/SoM/VBAT_SOM") (pinfunction "1") (pintype "passive"))
  )
	(footprint "sa800u-baseboard-hw-footprints:Spacer_SMD_M2.5_H4mm_Wurth_9774040151" (layer "B.Cu")
    (tedit 6215E167)
    (at 66.81 100.45 180)
    (descr "Spacer steel M2.5 h=4mm fi=5.1mm")
    (property "Author" "Antmicro")
    (property "License" "Apache-2.0")
    (property "MPN" "9774040151R")
    (property "Manufacturer" "Würth Elektronik")
    (property "Sheetfile" "m2.kicad_sch")
    (property "Sheetname" "M2")
    (attr smd)
    (fp_text reference "SP5" (at -1.1 3.4) (layer "B.SilkS")
      (effects (font (size 0.7 0.7) (thickness 0.15)) (justify left bottom mirror))
    )
    (fp_text value "Spacer_H4.0mm_9774040151" (at -11.7 -4.2) (layer "B.Fab")
      (effects (font (size 0.7 0.7) (thickness 0.15)) (justify left bottom mirror))
    )
    (fp_text user "${REFERENCE}" (at -2.551 -6.349) (layer "B.Fab") hide
      (effects (font (size 0.7 0.7) (thickness 0.15)) (justify left bottom mirror))
    )
    (fp_text user "License: Apache-2.0" (at -2.551 -8.749) (layer "B.Fab") hide
      (effects (font (size 0.7 0.7) (thickness 0.15)) (justify left bottom mirror))
    )
    (fp_text user "Author: Antmicro" (at -2.551 -7.549) (layer "B.Fab") hide
      (effects (font (size 0.7 0.7) (thickness 0.15)) (justify left bottom mirror))
    )
    (fp_circle (center 0 0) (end 2.499 0) (layer "B.Paste") (width 1) (fill none))
    (pad "1" thru_hole circle (at 0 0 180) (size 6 6) (drill 3.7) (layers *.Cu *.Mask)
      (net 1 "GND") (pinfunction "1") (pintype "passive") (solder_paste_margin -1.2))
  )
)
